# S9S_MB_2U (Grand Teton) — schematic netlist excerpt (pin names and nets, part order shuffled) for the footprints in the layout excerpt that follows; sources: Cadence DE-HDL packaged netlist, KiCad conversion of 03242023_DA0F0TMBIJ0_F0T_Motherboard_J_brd_V01_OCP.brd

R3610  Q_RES  4.7K 1% EMPTY  pkg 0402LF  page 172 : A = GND ; B = INA230_4_A1
R168  Q_RES  0 5% CHIP  pkg 0402LF  page 124 : A = PWRGD_CPU0_LVC1_R ; B = PWRGD_CPU0_BUF_R

(kicad_pcb
	(version 20260206)
	(generator "pcbnew")
	(generator_version "10.0")
	(general
		(thickness 1.6)
		(legacy_teardrops no)
	)
	(paper "A4")
	(title_block
		(title "03242023_DA0F0TMBIJ0_F0T_Motherboard_J_brd_V01_OCP.brd")
		(comment 1 "Grand Teton / footprints 2589-2590 of 6105")
	)
	(layers
		(0 "F.Cu" signal "TOP")
		(4 "In1.Cu" signal "GND")
		(6 "In2.Cu" signal "IN1")
		(8 "In3.Cu" signal "GND1")
		(10 "In4.Cu" signal "IN2")
		(12 "In5.Cu" signal "GND2")
		(14 "In6.Cu" signal "IN3")
		(16 "In7.Cu" signal "GND3")
		(18 "In8.Cu" signal "VCC")
		(20 "In9.Cu" signal "VCC1")
		(22 "In10.Cu" signal "GND4")
		(24 "In11.Cu" signal "IN4")
		(26 "In12.Cu" signal "GND5")
		(28 "In13.Cu" signal "IN5")
		(30 "In14.Cu" signal "GND6")
		(32 "In15.Cu" signal "IN6")
		(34 "In16.Cu" signal "GND7")
		(2 "B.Cu" signal "BOTTOM")
		(9 "F.Adhes" user "F.Adhesive")
		(11 "B.Adhes" user "B.Adhesive")
		(13 "F.Paste" user "Package Geometry/Pastemask Top")
		(15 "B.Paste" user "Package Geometry/Pastemask Bottom")
		(5 "F.SilkS" user "Ref Des/Silkscreen Top")
		(7 "B.SilkS" user "Ref Des/Silkscreen Bottom")
		(1 "F.Mask" user "Board Geometry/Soldermask Top")
		(3 "B.Mask" user "Board Geometry/Soldermask Bottom")
		(17 "Dwgs.User" user "User.Drawings")
		(19 "Cmts.User" user "User.Comments")
		(21 "Eco1.User" user "User.Eco1")
		(23 "Eco2.User" user "User.Eco2")
		(25 "Edge.Cuts" user "Board Geometry/Outline")
		(27 "Margin" user)
		(31 "F.CrtYd" user "Package Geometry/Place Bound Top")
		(29 "B.CrtYd" user "Package Geometry/Place Bound Bottom")
		(35 "F.Fab" user "Ref Des/Assembly Top")
		(33 "B.Fab" user "Ref Des/Assembly Bottom")
	)
	(footprint ""
		(layer "F.Cu")
		(at 148.197824 -53.436012)
		(property "Reference" "R3610"
			(at 0 0 0)
			(layer "F.SilkS")
			(hide yes)
			(effects
				(font
					(size 1.27 1.27)
				)
			)
		)
		(property "Value" ""
			(at 0 0 0)
			(layer "F.Fab")
			(effects
				(font
					(size 1.27 1.27)
				)
			)
		)
		(duplicate_pad_numbers_are_jumpers no)
		(fp_line
			(start -0.7874 -0.4064)
			(end 0.7874 -0.4064)
			(stroke
				(width 0.1524)
				(type default)
			)
			(layer "F.SilkS")
		)
		(fp_line
			(start -0.7874 0.4064)
			(end -0.7874 -0.4064)
			(stroke
				(width 0.1524)
				(type default)
			)
			(layer "F.SilkS")
		)
		(fp_line
			(start 0.7874 -0.4064)
			(end 0.7874 0.4064)
			(stroke
				(width 0.1524)
				(type default)
			)
			(layer "F.SilkS")
		)
		(fp_line
			(start 0.7874 0.4064)
			(end -0.7874 0.4064)
			(stroke
				(width 0.1524)
				(type default)
			)
			(layer "F.SilkS")
		)
		(fp_line
			(start -0.67945 -0.305054)
			(end -0.12065 -0.305054)
			(stroke
				(width 0.1)
				(type default)
			)
			(layer "F.Fab")
		)
		(fp_line
			(start -0.67945 0.3048)
			(end -0.67945 -0.305054)
			(stroke
				(width 0.1)
				(type default)
			)
			(layer "F.Fab")
		)
		(fp_line
			(start -0.12065 -0.305054)
			(end -0.12065 -0.2794)
			(stroke
				(width 0.1)
				(type default)
			)
			(layer "F.Fab")
		)
		(fp_line
			(start -0.12065 -0.2794)
			(end 0.12065 -0.2794)
			(stroke
				(width 0.1)
				(type default)
			)
			(layer "F.Fab")
		)
		(fp_line
			(start -0.12065 0.2794)
			(end -0.12065 0.3048)
			(stroke
				(width 0.1)
				(type default)
			)
			(layer "F.Fab")
		)
		(fp_line
			(start -0.12065 0.3048)
			(end -0.67945 0.3048)
			(stroke
				(width 0.1)
				(type default)
			)
			(layer "F.Fab")
		)
		(fp_line
			(start 0.120396 0.2794)
			(end -0.12065 0.2794)
			(stroke
				(width 0.1)
				(type default)
			)
			(layer "F.Fab")
		)
		(fp_line
			(start 0.120396 0.3048)
			(end 0.120396 0.2794)
			(stroke
				(width 0.1)
				(type default)
			)
			(layer "F.Fab")
		)
		(fp_line
			(start 0.12065 -0.3048)
			(end 0.67945 -0.3048)
			(stroke
				(width 0.1)
				(type default)
			)
			(layer "F.Fab")
		)
		(fp_line
			(start 0.12065 -0.2794)
			(end 0.12065 -0.3048)
			(stroke
				(width 0.1)
				(type default)
			)
			(layer "F.Fab")
		)
		(fp_line
			(start 0.67945 -0.3048)
			(end 0.67945 0.3048)
			(stroke
				(width 0.1)
				(type default)
			)
			(layer "F.Fab")
		)
		(fp_line
			(start 0.67945 0.3048)
			(end 0.120396 0.3048)
			(stroke
				(width 0.1)
				(type default)
			)
			(layer "F.Fab")
		)
		(pad "1" smd circle
			(at -0.40005 0)
			(size 0 0)
			(layers "F.Cu" "F.Mask" "F.Paste")
			(net "GND")
		)
		(pad "2" smd circle
			(at 0.40005 0)
			(size 0 0)
			(layers "F.Cu" "F.Mask" "F.Paste")
			(net "INA230_4_A1")
		)
	)
	(footprint ""
		(layer "F.Cu")
		(at 186.23788 -97.119948 -90)
		(property "Reference" "R168"
			(at 0 0 270)
			(layer "F.SilkS")
			(hide yes)
			(effects
				(font
					(size 1.27 1.27)
				)
			)
		)
		(property "Value" ""
			(at 0 0 270)
			(layer "F.Fab")
			(effects
				(font
					(size 1.27 1.27)
				)
			)
		)
		(duplicate_pad_numbers_are_jumpers no)
		(fp_line
			(start -0.7874 0.4064)
			(end -0.7874 -0.4064)
			(stroke
				(width 0.1524)
				(type default)
			)
			(layer "F.SilkS")
		)
		(fp_line
			(start 0.7874 0.4064)
			(end -0.7874 0.4064)
			(stroke
				(width 0.1524)
				(type default)
			)
			(layer "F.SilkS")
		)
		(fp_line
			(start -0.7874 -0.4064)
			(end 0.7874 -0.4064)
			(stroke
				(width 0.1524)
				(type default)
			)
			(layer "F.SilkS")
		)
		(fp_line
			(start 0.7874 -0.4064)
			(end 0.7874 0.4064)
			(stroke
				(width 0.1524)
				(type default)
			)
			(layer "F.SilkS")
		)
		(fp_line
			(start -0.67945 0.3048)
			(end -0.67945 -0.305054)
			(stroke
				(width 0.1)
				(type default)
			)
			(layer "F.Fab")
		)
		(fp_line
			(start -0.12065 0.3048)
			(end -0.67945 0.3048)
			(stroke
				(width 0.1)
				(type default)
			)
			(layer "F.Fab")
		)
		(fp_line
			(start 0.120396 0.3048)
			(end 0.120396 0.2794)
			(stroke
				(width 0.1)
				(type default)
			)
			(layer "F.Fab")
		)
		(fp_line
			(start 0.67945 0.3048)
			(end 0.120396 0.3048)
			(stroke
				(width 0.1)
				(type default)
			)
			(layer "F.Fab")
		)
		(fp_line
			(start -0.12065 0.2794)
			(end -0.12065 0.3048)
			(stroke
				(width 0.1)
				(type default)
			)
			(layer "F.Fab")
		)
		(fp_line
			(start 0.120396 0.2794)
			(end -0.12065 0.2794)
			(stroke
				(width 0.1)
				(type default)
			)
			(layer "F.Fab")
		)
		(fp_line
			(start -0.12065 -0.2794)
			(end 0.12065 -0.2794)
			(stroke
				(width 0.1)
				(type default)
			)
			(layer "F.Fab")
		)
		(fp_line
			(start 0.12065 -0.2794)
			(end 0.12065 -0.3048)
			(stroke
				(width 0.1)
				(type default)
			)
			(layer "F.Fab")
		)
		(fp_line
			(start 0.12065 -0.3048)
			(end 0.67945 -0.3048)
			(stroke
				(width 0.1)
				(type default)
			)
			(layer "F.Fab")
		)
		(fp_line
			(start 0.67945 -0.3048)
			(end 0.67945 0.3048)
			(stroke
				(width 0.1)
				(type default)
			)
			(layer "F.Fab")
		)
		(fp_line
			(start -0.67945 -0.305054)
			(end -0.12065 -0.305054)
			(stroke
				(width 0.1)
				(type default)
			)
			(layer "F.Fab")
		)
		(fp_line
			(start -0.12065 -0.305054)
			(end -0.12065 -0.2794)
			(stroke
				(width 0.1)
				(type default)
			)
			(layer "F.Fab")
		)
		(pad "1" smd circle
			(at -0.40005 0 270)
			(size 0 0)
			(layers "F.Cu" "F.Mask" "F.Paste")
			(net "PWRGD_CPU0_LVC1_R")
		)
		(pad "2" smd circle
			(at 0.40005 0 270)
			(size 0 0)
			(layers "F.Cu" "F.Mask" "F.Paste")
			(net "PWRGD_CPU0_BUF_R")
		)
	)
)
